# S9S_MB_2U (Grand Teton) — schematic netlist excerpt (pin names and nets, part order shuffled) for the footprints in the layout excerpt that follows; sources: Cadence DE-HDL packaged netlist, KiCad conversion of 03242023_DA0F0TMBIJ0_F0T_Motherboard_J_brd_V01_OCP.brd

R1402  Q_RES  2K 1% CHIP  pkg 0402LF  page 219 : A = PWRGD_SYS_PWROK ; B = GND
R3478  Q_RES  33.2 1% CHIP  pkg 0402LF  page 213 : A = GPU_FPGA_EROT_RST_N ; B = GPU_FPGA_EROT_RST_R_N

(kicad_pcb
	(version 20260206)
	(generator "pcbnew")
	(generator_version "10.0")
	(general
		(thickness 1.6)
		(legacy_teardrops no)
	)
	(paper "A4")
	(title_block
		(title "03242023_DA0F0TMBIJ0_F0T_Motherboard_J_brd_V01_OCP.brd")
		(comment 1 "Grand Teton / footprints 5781-5782 of 6105")
	)
	(layers
		(0 "F.Cu" signal "TOP")
		(4 "In1.Cu" signal "GND")
		(6 "In2.Cu" signal "IN1")
		(8 "In3.Cu" signal "GND1")
		(10 "In4.Cu" signal "IN2")
		(12 "In5.Cu" signal "GND2")
		(14 "In6.Cu" signal "IN3")
		(16 "In7.Cu" signal "GND3")
		(18 "In8.Cu" signal "VCC")
		(20 "In9.Cu" signal "VCC1")
		(22 "In10.Cu" signal "GND4")
		(24 "In11.Cu" signal "IN4")
		(26 "In12.Cu" signal "GND5")
		(28 "In13.Cu" signal "IN5")
		(30 "In14.Cu" signal "GND6")
		(32 "In15.Cu" signal "IN6")
		(34 "In16.Cu" signal "GND7")
		(2 "B.Cu" signal "BOTTOM")
		(9 "F.Adhes" user "F.Adhesive")
		(11 "B.Adhes" user "B.Adhesive")
		(13 "F.Paste" user "Package Geometry/Pastemask Top")
		(15 "B.Paste" user "Package Geometry/Pastemask Bottom")
		(5 "F.SilkS" user "Ref Des/Silkscreen Top")
		(7 "B.SilkS" user "Ref Des/Silkscreen Bottom")
		(1 "F.Mask" user "Board Geometry/Soldermask Top")
		(3 "B.Mask" user "Board Geometry/Soldermask Bottom")
		(17 "Dwgs.User" user "User.Drawings")
		(19 "Cmts.User" user "User.Comments")
		(21 "Eco1.User" user "User.Eco1")
		(23 "Eco2.User" user "User.Eco2")
		(25 "Edge.Cuts" user "Board Geometry/Outline")
		(27 "Margin" user)
		(31 "F.CrtYd" user "Package Geometry/Place Bound Top")
		(29 "B.CrtYd" user "Package Geometry/Place Bound Bottom")
		(35 "F.Fab" user "Ref Des/Assembly Top")
		(33 "B.Fab" user "Ref Des/Assembly Bottom")
	)
	(footprint ""
		(layer "B.Cu")
		(at 320.776092 -37.442902 45)
		(property "Reference" "R1402"
			(at 0 0 45)
			(layer "B.SilkS")
			(hide yes)
			(effects
				(font
					(size 1.27 1.27)
				)
				(justify mirror)
			)
		)
		(property "Value" ""
			(at 0 0 45)
			(layer "B.Fab")
			(effects
				(font
					(size 1.27 1.27)
				)
				(justify mirror)
			)
		)
		(duplicate_pad_numbers_are_jumpers no)
		(fp_line
			(start -0.787389 -0.406267)
			(end -0.787389 0.406267)
			(stroke
				(width 0.1524)
				(type default)
			)
			(layer "B.SilkS")
		)
		(fp_line
			(start -0.787389 0.406267)
			(end 0.787389 0.406267)
			(stroke
				(width 0.1524)
				(type default)
			)
			(layer "B.SilkS")
		)
		(fp_line
			(start 0.787389 -0.406267)
			(end -0.787389 -0.406267)
			(stroke
				(width 0.1524)
				(type default)
			)
			(layer "B.SilkS")
		)
		(fp_line
			(start 0.787389 0.406267)
			(end 0.787389 -0.406267)
			(stroke
				(width 0.1524)
				(type default)
			)
			(layer "B.SilkS")
		)
		(fp_line
			(start -0.679446 -0.30479)
			(end -0.679446 0.30479)
			(stroke
				(width 0.1)
				(type default)
			)
			(layer "B.Fab")
		)
		(fp_line
			(start -0.120515 -0.30479)
			(end -0.679446 -0.30479)
			(stroke
				(width 0.1)
				(type default)
			)
			(layer "B.Fab")
		)
		(fp_line
			(start -0.120695 -0.279466)
			(end -0.120515 -0.30479)
			(stroke
				(width 0.1)
				(type default)
			)
			(layer "B.Fab")
		)
		(fp_line
			(start -0.679446 0.30479)
			(end -0.120515 0.30479)
			(stroke
				(width 0.1)
				(type default)
			)
			(layer "B.Fab")
		)
		(fp_line
			(start 0.120695 -0.304969)
			(end 0.120695 -0.279466)
			(stroke
				(width 0.1)
				(type default)
			)
			(layer "B.Fab")
		)
		(fp_line
			(start 0.120695 -0.279466)
			(end -0.120695 -0.279466)
			(stroke
				(width 0.1)
				(type default)
			)
			(layer "B.Fab")
		)
		(fp_line
			(start -0.120335 0.279466)
			(end 0.120695 0.279466)
			(stroke
				(width 0.1)
				(type default)
			)
			(layer "B.Fab")
		)
		(fp_line
			(start -0.120515 0.30479)
			(end -0.120335 0.279466)
			(stroke
				(width 0.1)
				(type default)
			)
			(layer "B.Fab")
		)
		(fp_line
			(start 0.679446 -0.305149)
			(end 0.120695 -0.304969)
			(stroke
				(width 0.1)
				(type default)
			)
			(layer "B.Fab")
		)
		(fp_line
			(start 0.120695 0.279466)
			(end 0.120515 0.30479)
			(stroke
				(width 0.1)
				(type default)
			)
			(layer "B.Fab")
		)
		(fp_line
			(start 0.120515 0.30479)
			(end 0.679446 0.30479)
			(stroke
				(width 0.1)
				(type default)
			)
			(layer "B.Fab")
		)
		(fp_line
			(start 0.679446 0.30479)
			(end 0.679446 -0.305149)
			(stroke
				(width 0.1)
				(type default)
			)
			(layer "B.Fab")
		)
		(pad "1" smd circle
			(at 0.40005 0 225)
			(size 0 0)
			(layers "B.Cu" "B.Mask" "B.Paste")
			(net "PWRGD_SYS_PWROK")
		)
		(pad "2" smd circle
			(at -0.40005 0 225)
			(size 0 0)
			(layers "B.Cu" "B.Mask" "B.Paste")
			(net "GND")
		)
	)
	(footprint ""
		(layer "B.Cu")
		(at 157.02788 -115.026948 180)
		(property "Reference" "R3478"
			(at 0 0 0)
			(layer "B.SilkS")
			(hide yes)
			(effects
				(font
					(size 1.27 1.27)
				)
				(justify mirror)
			)
		)
		(property "Value" ""
			(at 0 0 0)
			(layer "B.Fab")
			(effects
				(font
					(size 1.27 1.27)
				)
				(justify mirror)
			)
		)
		(duplicate_pad_numbers_are_jumpers no)
		(fp_line
			(start 0.7874 0.4064)
			(end 0.7874 -0.4064)
			(stroke
				(width 0.1524)
				(type default)
			)
			(layer "B.SilkS")
		)
		(fp_line
			(start 0.7874 -0.4064)
			(end -0.7874 -0.4064)
			(stroke
				(width 0.1524)
				(type default)
			)
			(layer "B.SilkS")
		)
		(fp_line
			(start -0.7874 0.4064)
			(end 0.7874 0.4064)
			(stroke
				(width 0.1524)
				(type default)
			)
			(layer "B.SilkS")
		)
		(fp_line
			(start -0.7874 -0.4064)
			(end -0.7874 0.4064)
			(stroke
				(width 0.1524)
				(type default)
			)
			(layer "B.SilkS")
		)
		(fp_line
			(start 0.67945 0.3048)
			(end 0.67945 -0.305054)
			(stroke
				(width 0.1)
				(type default)
			)
			(layer "B.Fab")
		)
		(fp_line
			(start 0.67945 -0.305054)
			(end 0.12065 -0.305054)
			(stroke
				(width 0.1)
				(type default)
			)
			(layer "B.Fab")
		)
		(fp_line
			(start 0.12065 0.3048)
			(end 0.67945 0.3048)
			(stroke
				(width 0.1)
				(type default)
			)
			(layer "B.Fab")
		)
		(fp_line
			(start 0.12065 0.2794)
			(end 0.12065 0.3048)
			(stroke
				(width 0.1)
				(type default)
			)
			(layer "B.Fab")
		)
		(fp_line
			(start 0.12065 -0.2794)
			(end -0.12065 -0.2794)
			(stroke
				(width 0.1)
				(type default)
			)
			(layer "B.Fab")
		)
		(fp_line
			(start 0.12065 -0.305054)
			(end 0.12065 -0.2794)
			(stroke
				(width 0.1)
				(type default)
			)
			(layer "B.Fab")
		)
		(fp_line
			(start -0.120396 0.3048)
			(end -0.120396 0.2794)
			(stroke
				(width 0.1)
				(type default)
			)
			(layer "B.Fab")
		)
		(fp_line
			(start -0.120396 0.2794)
			(end 0.12065 0.2794)
			(stroke
				(width 0.1)
				(type default)
			)
			(layer "B.Fab")
		)
		(fp_line
			(start -0.12065 -0.2794)
			(end -0.12065 -0.3048)
			(stroke
				(width 0.1)
				(type default)
			)
			(layer "B.Fab")
		)
		(fp_line
			(start -0.12065 -0.3048)
			(end -0.67945 -0.3048)
			(stroke
				(width 0.1)
				(type default)
			)
			(layer "B.Fab")
		)
		(fp_line
			(start -0.67945 0.3048)
			(end -0.120396 0.3048)
			(stroke
				(width 0.1)
				(type default)
			)
			(layer "B.Fab")
		)
		(fp_line
			(start -0.67945 -0.3048)
			(end -0.67945 0.3048)
			(stroke
				(width 0.1)
				(type default)
			)
			(layer "B.Fab")
		)
		(pad "1" smd circle
			(at 0.40005 0)
			(size 0 0)
			(layers "B.Cu" "B.Mask" "B.Paste")
			(net "GPU_FPGA_EROT_RST_N")
		)
		(pad "2" smd circle
			(at -0.40005 0)
			(size 0 0)
			(layers "B.Cu" "B.Mask" "B.Paste")
			(net "GPU_FPGA_EROT_RST_R_N")
		)
	)
)
